FILE_TYPE = MULTI_PHYS_TABLE;
PART 'TTL1G07_A'
{========================================================================================================================================================================================================================================}
:VALUE      | PACK_TYPE | MATERIAL | PART_NUMBER      = EnvComp                            | PART_NUMBER  | JEDEC_TYPE      | DESCRIPTION                                      | HEIGHT     | COMPONENT_TYPE | LEAD_LENGTH  |  LPID  | SPEED_URL | Status |RPL| AML | Bus_Unit | Days ;
{========================================================================================================================================================================================================================================}
'74LVC1G07' | 'SOP'     | 'IC'     | 'C88419-001' (!) = 'YES;YES;YES;UNK;ok;VLD'           | 'C88419-001' | 'SSOP5_53_65MA' | '74LVC1G07 BUFFER'                               | '0.043 IN' | 'SMALLSMT'     | ''           | '374'  | 'http://speed.intel.com:8081/speed/module/pdm/item/pdm_item_detail_direct.asp?item_cde=C88419-001&item_rev=01&url_param=unused' | 'Approved' | 'YES' | '6' | 'SMO_IC' | '28' 
'74LVC1G07' | 'SOP'     | 'EMPTY'  | 'C88419-001' (!) = 'YES;YES;YES;UNK;ok;VLD'           | 'C88419-001' | 'SSOP5_53_65MA' | '74LVC1G07 BUFFER'                               | '0.043 IN' | 'SMALLSMT'     | ''           | '374'  | 'http://speed.intel.com:8081/speed/module/pdm/item/pdm_item_detail_direct.asp?item_cde=C88419-001&item_rev=01&url_param=unused' | 'Approved' | 'YES' | '6' | 'SMO_IC' | '28' 
END_PART
END.
